# T6G (Grand Teton) — schematic netlist excerpt (pin names and nets, part order shuffled) for the footprints in the layout excerpt that follows; sources: Cadence DE-HDL packaged netlist, KiCad conversion of 04192023_DAF0TMB3IC0_F0TG_MB_C_brd_V02_OCP.brd

R3428  Q_RES  100K 1% EMPTY  pkg 0402LF  page 126 : A = GPU_FPGA_THERM_OVERT_N ; B = GND
PR2511  Q_RES  1 1% CHIP  pkg 0402LF  page 266 : A = P12V_HSC_ADC_P ; B = P12V_HSC_SENSE2_R2_P
C381  Q_CAP  0.1UF 10V 10% X7S  pkg C0201  page 345 : A = P1V8_CPU1_RT2_1A ; B = GND

(kicad_pcb
	(version 20260206)
	(generator "pcbnew")
	(generator_version "10.0")
	(general
		(thickness 1.6)
		(legacy_teardrops no)
	)
	(paper "A4")
	(title_block
		(title "04192023_DAF0TMB3IC0_F0TG_MB_C_brd_V02_OCP.brd")
		(comment 1 "Grand Teton / footprints 6430-6432 of 8354")
	)
	(layers
		(0 "F.Cu" signal "TOP")
		(4 "In1.Cu" signal "GND")
		(6 "In2.Cu" signal "IN1")
		(8 "In3.Cu" signal "GND1")
		(10 "In4.Cu" signal "IN2")
		(12 "In5.Cu" signal "GND2")
		(14 "In6.Cu" signal "IN3")
		(16 "In7.Cu" signal "GND3")
		(18 "In8.Cu" signal "VCC")
		(20 "In9.Cu" signal "VCC1")
		(22 "In10.Cu" signal "GND4")
		(24 "In11.Cu" signal "IN4")
		(26 "In12.Cu" signal "GND5")
		(28 "In13.Cu" signal "IN5")
		(30 "In14.Cu" signal "GND6")
		(32 "In15.Cu" signal "IN6")
		(34 "In16.Cu" signal "GND7")
		(2 "B.Cu" signal "BOTTOM")
		(9 "F.Adhes" user "F.Adhesive")
		(11 "B.Adhes" user "B.Adhesive")
		(13 "F.Paste" user "Package Geometry/Pastemask Top")
		(15 "B.Paste" user "Package Geometry/Pastemask Bottom")
		(5 "F.SilkS" user "Ref Des/Silkscreen Top")
		(7 "B.SilkS" user "Ref Des/Silkscreen Bottom")
		(1 "F.Mask" user "Board Geometry/Soldermask Top")
		(3 "B.Mask" user "Board Geometry/Soldermask Bottom")
		(17 "Dwgs.User" user "User.Drawings")
		(19 "Cmts.User" user "User.Comments")
		(21 "Eco1.User" user "User.Eco1")
		(23 "Eco2.User" user "User.Eco2")
		(25 "Edge.Cuts" user "Board Geometry/Outline")
		(27 "Margin" user)
		(31 "F.CrtYd" user "Package Geometry/Place Bound Top")
		(29 "B.CrtYd" user "Package Geometry/Place Bound Bottom")
		(35 "F.Fab" user "Ref Des/Assembly Top")
		(33 "B.Fab" user "Ref Des/Assembly Bottom")
	)
	(footprint ""
		(layer "B.Cu")
		(at 52.782978 -433.682902 -90)
		(property "Reference" "R3428"
			(at 0 0 90)
			(layer "B.SilkS")
			(hide yes)
			(effects
				(font
					(size 1.27 1.27)
				)
				(justify mirror)
			)
		)
		(property "Value" ""
			(at 0 0 90)
			(layer "B.Fab")
			(effects
				(font
					(size 1.27 1.27)
				)
				(justify mirror)
			)
		)
		(duplicate_pad_numbers_are_jumpers no)
		(fp_line
			(start -0.7874 0.4064)
			(end 0.7874 0.4064)
			(stroke
				(width 0.1524)
				(type default)
			)
			(layer "B.SilkS")
		)
		(fp_line
			(start 0.7874 0.4064)
			(end 0.7874 -0.4064)
			(stroke
				(width 0.1524)
				(type default)
			)
			(layer "B.SilkS")
		)
		(fp_line
			(start -0.7874 -0.4064)
			(end -0.7874 0.4064)
			(stroke
				(width 0.1524)
				(type default)
			)
			(layer "B.SilkS")
		)
		(fp_line
			(start 0.7874 -0.4064)
			(end -0.7874 -0.4064)
			(stroke
				(width 0.1524)
				(type default)
			)
			(layer "B.SilkS")
		)
		(fp_line
			(start -0.67945 0.3048)
			(end -0.120396 0.3048)
			(stroke
				(width 0.1)
				(type default)
			)
			(layer "B.Fab")
		)
		(fp_line
			(start -0.120396 0.3048)
			(end -0.120396 0.2794)
			(stroke
				(width 0.1)
				(type default)
			)
			(layer "B.Fab")
		)
		(fp_line
			(start 0.12065 0.3048)
			(end 0.67945 0.3048)
			(stroke
				(width 0.1)
				(type default)
			)
			(layer "B.Fab")
		)
		(fp_line
			(start 0.67945 0.3048)
			(end 0.67945 -0.305054)
			(stroke
				(width 0.1)
				(type default)
			)
			(layer "B.Fab")
		)
		(fp_line
			(start -0.120396 0.2794)
			(end 0.12065 0.2794)
			(stroke
				(width 0.1)
				(type default)
			)
			(layer "B.Fab")
		)
		(fp_line
			(start 0.12065 0.2794)
			(end 0.12065 0.3048)
			(stroke
				(width 0.1)
				(type default)
			)
			(layer "B.Fab")
		)
		(fp_line
			(start -0.12065 -0.2794)
			(end -0.12065 -0.3048)
			(stroke
				(width 0.1)
				(type default)
			)
			(layer "B.Fab")
		)
		(fp_line
			(start 0.12065 -0.2794)
			(end -0.12065 -0.2794)
			(stroke
				(width 0.1)
				(type default)
			)
			(layer "B.Fab")
		)
		(fp_line
			(start -0.67945 -0.3048)
			(end -0.67945 0.3048)
			(stroke
				(width 0.1)
				(type default)
			)
			(layer "B.Fab")
		)
		(fp_line
			(start -0.12065 -0.3048)
			(end -0.67945 -0.3048)
			(stroke
				(width 0.1)
				(type default)
			)
			(layer "B.Fab")
		)
		(fp_line
			(start 0.12065 -0.305054)
			(end 0.12065 -0.2794)
			(stroke
				(width 0.1)
				(type default)
			)
			(layer "B.Fab")
		)
		(fp_line
			(start 0.67945 -0.305054)
			(end 0.12065 -0.305054)
			(stroke
				(width 0.1)
				(type default)
			)
			(layer "B.Fab")
		)
		(pad "1" smd circle
			(at 0.40005 0 90)
			(size 0 0)
			(layers "B.Cu" "B.Mask" "B.Paste")
			(net "GPU_FPGA_THERM_OVERT_N")
		)
		(pad "2" smd circle
			(at -0.40005 0 90)
			(size 0 0)
			(layers "B.Cu" "B.Mask" "B.Paste")
			(net "GND")
		)
	)
	(footprint ""
		(layer "B.Cu")
		(at 208.461356 -385.136136)
		(property "Reference" "PR2511"
			(at 0 0 0)
			(layer "B.SilkS")
			(hide yes)
			(effects
				(font
					(size 1.27 1.27)
				)
				(justify mirror)
			)
		)
		(property "Value" ""
			(at 0 0 0)
			(layer "B.Fab")
			(effects
				(font
					(size 1.27 1.27)
				)
				(justify mirror)
			)
		)
		(duplicate_pad_numbers_are_jumpers no)
		(fp_line
			(start -0.7874 -0.4064)
			(end -0.7874 0.4064)
			(stroke
				(width 0.1524)
				(type default)
			)
			(layer "B.SilkS")
		)
		(fp_line
			(start -0.7874 0.4064)
			(end 0.7874 0.4064)
			(stroke
				(width 0.1524)
				(type default)
			)
			(layer "B.SilkS")
		)
		(fp_line
			(start 0.7874 -0.4064)
			(end -0.7874 -0.4064)
			(stroke
				(width 0.1524)
				(type default)
			)
			(layer "B.SilkS")
		)
		(fp_line
			(start 0.7874 0.4064)
			(end 0.7874 -0.4064)
			(stroke
				(width 0.1524)
				(type default)
			)
			(layer "B.SilkS")
		)
		(fp_line
			(start -0.67945 -0.3048)
			(end -0.67945 0.3048)
			(stroke
				(width 0.1)
				(type default)
			)
			(layer "B.Fab")
		)
		(fp_line
			(start -0.67945 0.3048)
			(end -0.120396 0.3048)
			(stroke
				(width 0.1)
				(type default)
			)
			(layer "B.Fab")
		)
		(fp_line
			(start -0.12065 -0.3048)
			(end -0.67945 -0.3048)
			(stroke
				(width 0.1)
				(type default)
			)
			(layer "B.Fab")
		)
		(fp_line
			(start -0.12065 -0.2794)
			(end -0.12065 -0.3048)
			(stroke
				(width 0.1)
				(type default)
			)
			(layer "B.Fab")
		)
		(fp_line
			(start -0.120396 0.2794)
			(end 0.12065 0.2794)
			(stroke
				(width 0.1)
				(type default)
			)
			(layer "B.Fab")
		)
		(fp_line
			(start -0.120396 0.3048)
			(end -0.120396 0.2794)
			(stroke
				(width 0.1)
				(type default)
			)
			(layer "B.Fab")
		)
		(fp_line
			(start 0.12065 -0.305054)
			(end 0.12065 -0.2794)
			(stroke
				(width 0.1)
				(type default)
			)
			(layer "B.Fab")
		)
		(fp_line
			(start 0.12065 -0.2794)
			(end -0.12065 -0.2794)
			(stroke
				(width 0.1)
				(type default)
			)
			(layer "B.Fab")
		)
		(fp_line
			(start 0.12065 0.2794)
			(end 0.12065 0.3048)
			(stroke
				(width 0.1)
				(type default)
			)
			(layer "B.Fab")
		)
		(fp_line
			(start 0.12065 0.3048)
			(end 0.67945 0.3048)
			(stroke
				(width 0.1)
				(type default)
			)
			(layer "B.Fab")
		)
		(fp_line
			(start 0.67945 -0.305054)
			(end 0.12065 -0.305054)
			(stroke
				(width 0.1)
				(type default)
			)
			(layer "B.Fab")
		)
		(fp_line
			(start 0.67945 0.3048)
			(end 0.67945 -0.305054)
			(stroke
				(width 0.1)
				(type default)
			)
			(layer "B.Fab")
		)
		(pad "1" smd circle
			(at 0.40005 0 180)
			(size 0 0)
			(layers "B.Cu" "B.Mask" "B.Paste")
			(net "P12V_HSC_ADC_P")
		)
		(pad "2" smd circle
			(at -0.40005 0 180)
			(size 0 0)
			(layers "B.Cu" "B.Mask" "B.Paste")
			(net "P12V_HSC_SENSE2_R2_P")
		)
	)
	(footprint ""
		(layer "B.Cu")
		(at 154.206194 -386.766562 90)
		(property "Reference" "C381"
			(at 0 0 90)
			(layer "B.SilkS")
			(hide yes)
			(effects
				(font
					(size 1.27 1.27)
				)
				(justify mirror)
			)
		)
		(property "Value" ""
			(at 0 0 90)
			(layer "B.Fab")
			(effects
				(font
					(size 1.27 1.27)
				)
				(justify mirror)
			)
		)
		(duplicate_pad_numbers_are_jumpers no)
		(fp_line
			(start 0.299974 -0.150114)
			(end -0.299974 -0.150114)
			(stroke
				(width 0.1)
				(type default)
			)
			(layer "B.Fab")
		)
		(fp_line
			(start -0.299974 -0.150114)
			(end -0.299974 0.150114)
			(stroke
				(width 0.1)
				(type default)
			)
			(layer "B.Fab")
		)
		(fp_line
			(start 0.299974 0.150114)
			(end 0.299974 -0.150114)
			(stroke
				(width 0.1)
				(type default)
			)
			(layer "B.Fab")
		)
		(fp_line
			(start -0.299974 0.150114)
			(end 0.299974 0.150114)
			(stroke
				(width 0.1)
				(type default)
			)
			(layer "B.Fab")
		)
		(pad "1" smd rect
			(at 0.2667 0 270)
			(size 0.3048 0.381)
			(layers "B.Cu" "B.Mask" "B.Paste")
			(net "P1V8_CPU1_RT2_1A")
		)
		(pad "2" smd rect
			(at -0.2667 0 270)
			(size 0.3048 0.381)
			(layers "B.Cu" "B.Mask" "B.Paste")
			(net "GND")
		)
	)
)
